(kicad_pcb
	(version 20260206)
	(generator "pcbnew")
	(generator_version "10.0")
	(general
		(thickness 1.6)
		(legacy_teardrops no)
	)
	(paper "A4")
	(title_block
		(title "timecard-production-celestica-r4006 — R4006-B0001-02_R01.brd")
		(comment 1 "Time Appliance Project (Time Card) / footprints 434-438 of 1113")
	)
	(layers
		(0 "F.Cu" signal "TOP")
		(4 "In1.Cu" signal "L02_GND1")
		(6 "In2.Cu" signal "L03_SIG1")
		(8 "In3.Cu" signal "L04_GND2")
		(10 "In4.Cu" signal "L05_VCC1")
		(12 "In5.Cu" signal "L06_VCC2")
		(14 "In6.Cu" signal "L07_GND3")
		(16 "In7.Cu" signal "L08_SIG2")
		(18 "In8.Cu" signal "L09_GND4")
		(2 "B.Cu" signal "BOTTOM")
		(9 "F.Adhes" user "F.Adhesive")
		(11 "B.Adhes" user "B.Adhesive")
		(13 "F.Paste" user "Package Geometry/Pastemask Top")
		(15 "B.Paste" user "Package Geometry/Pastemask Bottom")
		(5 "F.SilkS" user "Ref Des/Silkscreen Top")
		(7 "B.SilkS" user "Ref Des/Silkscreen Bottom")
		(1 "F.Mask" user "Board Geometry/Soldermask Top")
		(3 "B.Mask" user "Board Geometry/Soldermask Bottom")
		(17 "Dwgs.User" user "User.Drawings")
		(19 "Cmts.User" user "User.Comments")
		(21 "Eco1.User" user "User.Eco1")
		(23 "Eco2.User" user "User.Eco2")
		(25 "Edge.Cuts" user "Board Geometry/Outline")
		(27 "Margin" user)
		(31 "F.CrtYd" user "Package Geometry/Place Bound Top")
		(29 "B.CrtYd" user "Package Geometry/Place Bound Bottom")
		(35 "F.Fab" user "Ref Des/Assembly Top")
		(33 "B.Fab" user "Ref Des/Assembly Bottom")
	)
	(footprint ""
		(layer "F.Cu")
		(at 150.343108 -49.01311 90)
		(property "Reference" "R66"
			(at 0.00889 -3.237738 90)
			(unlocked yes)
			(layer "F.SilkS")
			(effects
				(font
					(size 0.7874 0.5842)
					(thickness 0.1524)
				)
			)
		)
		(property "Value" "VAL*"
			(at 0.02032 2.13233 90)
			(unlocked yes)
			(layer "F.Fab")
			(hide yes)
			(effects
				(font
					(size 0.7874 0.5842)
					(thickness 0.1524)
				)
			)
		)
		(property "Device Type" "RESISTOR-G155-133R0-01,33OHM,1%"
			(at 0.008382 1.210564 90)
			(unlocked yes)
			(layer "F.Fab")
			(hide yes)
			(effects
				(font
					(size 0.7874 0.5842)
					(thickness 0.1524)
				)
			)
		)
		(property "User Part Number" "PARTNUM*"
			(at 0.02032 4.024884 90)
			(unlocked yes)
			(layer "Cmts.User")
			(hide yes)
			(effects
				(font
					(size 0.7874 0.5842)
					(thickness 0.1524)
				)
			)
		)
		(property "Tolerance" "TOL*"
			(at 0.044704 3.05435 90)
			(unlocked yes)
			(layer "Cmts.User")
			(hide yes)
			(effects
				(font
					(size 0.7874 0.5842)
					(thickness 0.1524)
				)
			)
		)
		(duplicate_pad_numbers_are_jumpers no)
		(fp_line
			(start 1.143 -0.5588)
			(end -1.143 -0.5588)
			(stroke
				(width 0.1)
				(type default)
			)
			(layer "F.SilkS")
		)
		(fp_line
			(start -1.143 -0.5588)
			(end -1.143 0.5588)
			(stroke
				(width 0.1)
				(type default)
			)
			(layer "F.SilkS")
		)
		(fp_line
			(start 1.143 0.5588)
			(end 1.143 -0.5588)
			(stroke
				(width 0.1)
				(type default)
			)
			(layer "F.SilkS")
		)
		(fp_line
			(start -1.143 0.5588)
			(end 1.143 0.5588)
			(stroke
				(width 0.1)
				(type default)
			)
			(layer "F.SilkS")
		)
		(fp_rect
			(start 1.143 0.5588)
			(end -1.143 -0.5588)
			(stroke
				(width 0)
				(type default)
			)
			(fill no)
			(layer "F.CrtYd")
		)
		(fp_line
			(start 0.508 -0.3048)
			(end -0.508 -0.3048)
			(stroke
				(width 0.1)
				(type default)
			)
			(layer "F.Fab")
		)
		(fp_line
			(start -0.508 -0.3048)
			(end -0.508 0.3048)
			(stroke
				(width 0.1)
				(type default)
			)
			(layer "F.Fab")
		)
		(fp_line
			(start 0.508 0.3048)
			(end 0.508 -0.3048)
			(stroke
				(width 0.1)
				(type default)
			)
			(layer "F.Fab")
		)
		(fp_line
			(start -0.508 0.3048)
			(end 0.508 0.3048)
			(stroke
				(width 0.1)
				(type default)
			)
			(layer "F.Fab")
		)
		(pad "1" smd rect
			(at -0.5334 0 90)
			(size 0.7112 0.6096)
			(layers "F.Cu" "F.Mask" "F.Paste")
			(net "SHT3X_I2C_SDA")
		)
		(pad "2" smd rect
			(at 0.5334 0 90)
			(size 0.7112 0.6096)
			(layers "F.Cu" "F.Mask" "F.Paste")
			(net "R_SHT3X_I2C_SDA")
		)
		(zone
			(layer "F.Cu")
			(hatch none 0.5)
			(connect_pads
				(clearance 0)
			)
			(min_thickness 0.25)
			(keepout
				(tracks allowed)
				(vias not_allowed)
				(pads allowed)
				(copperpour not_allowed)
				(footprints allowed)
			)
			(placement
				(enabled no)
				(sheetname "")
			)
			(fill
				(thermal_gap 0.5)
				(thermal_bridge_width 0.5)
				(island_removal_mode 0)
			)
			(polygon
				(pts
					(xy 150.647908 -49.08931) (xy 150.038308 -49.08931) (xy 150.038308 -48.93691) (xy 150.647908 -48.93691)
				)
			)
		)
	)
	(footprint ""
		(layer "F.Cu")
		(at 121.539 -89.535 -90)
		(property "Reference" "R116"
			(at 3.429 0.21463 90)
			(unlocked yes)
			(layer "F.SilkS")
			(effects
				(font
					(size 0.7874 0.5842)
					(thickness 0.1524)
				)
			)
		)
		(property "Value" "VAL*"
			(at 0.02032 2.13233 270)
			(unlocked yes)
			(layer "F.Fab")
			(hide yes)
			(effects
				(font
					(size 0.7874 0.5842)
					(thickness 0.1524)
				)
			)
		)
		(property "Device Type" "RESISTOR-G155-133R0-01,33OHM,1%"
			(at 0.008382 1.210564 270)
			(unlocked yes)
			(layer "F.Fab")
			(hide yes)
			(effects
				(font
					(size 0.7874 0.5842)
					(thickness 0.1524)
				)
			)
		)
		(property "User Part Number" "PARTNUM*"
			(at 0.02032 4.024884 270)
			(unlocked yes)
			(layer "Cmts.User")
			(hide yes)
			(effects
				(font
					(size 0.7874 0.5842)
					(thickness 0.1524)
				)
			)
		)
		(property "Tolerance" "TOL*"
			(at 0.044704 3.05435 270)
			(unlocked yes)
			(layer "Cmts.User")
			(hide yes)
			(effects
				(font
					(size 0.7874 0.5842)
					(thickness 0.1524)
				)
			)
		)
		(duplicate_pad_numbers_are_jumpers no)
		(fp_line
			(start -1.143 0.5588)
			(end 1.143 0.5588)
			(stroke
				(width 0.1)
				(type default)
			)
			(layer "F.SilkS")
		)
		(fp_line
			(start 1.143 0.5588)
			(end 1.143 -0.5588)
			(stroke
				(width 0.1)
				(type default)
			)
			(layer "F.SilkS")
		)
		(fp_line
			(start -1.143 -0.5588)
			(end -1.143 0.5588)
			(stroke
				(width 0.1)
				(type default)
			)
			(layer "F.SilkS")
		)
		(fp_line
			(start 1.143 -0.5588)
			(end -1.143 -0.5588)
			(stroke
				(width 0.1)
				(type default)
			)
			(layer "F.SilkS")
		)
		(fp_rect
			(start 1.143 -0.5588)
			(end -1.143 0.5588)
			(stroke
				(width 0)
				(type default)
			)
			(fill no)
			(layer "F.CrtYd")
		)
		(fp_line
			(start -0.508 0.3048)
			(end 0.508 0.3048)
			(stroke
				(width 0.1)
				(type default)
			)
			(layer "F.Fab")
		)
		(fp_line
			(start 0.508 0.3048)
			(end 0.508 -0.3048)
			(stroke
				(width 0.1)
				(type default)
			)
			(layer "F.Fab")
		)
		(fp_line
			(start -0.508 -0.3048)
			(end -0.508 0.3048)
			(stroke
				(width 0.1)
				(type default)
			)
			(layer "F.Fab")
		)
		(fp_line
			(start 0.508 -0.3048)
			(end -0.508 -0.3048)
			(stroke
				(width 0.1)
				(type default)
			)
			(layer "F.Fab")
		)
		(pad "1" smd rect
			(at -0.5334 0 270)
			(size 0.7112 0.6096)
			(layers "F.Cu" "F.Mask" "F.Paste")
			(net "GPS_RST_N")
		)
		(pad "2" smd rect
			(at 0.5334 0 270)
			(size 0.7112 0.6096)
			(layers "F.Cu" "F.Mask" "F.Paste")
			(net "FPGA_OUT_GPS_RST_N")
		)
		(zone
			(layer "F.Cu")
			(hatch none 0.5)
			(connect_pads
				(clearance 0)
			)
			(min_thickness 0.25)
			(keepout
				(tracks allowed)
				(vias not_allowed)
				(pads allowed)
				(copperpour not_allowed)
				(footprints allowed)
			)
			(placement
				(enabled no)
				(sheetname "")
			)
			(fill
				(thermal_gap 0.5)
				(thermal_bridge_width 0.5)
				(island_removal_mode 0)
			)
			(polygon
				(pts
					(xy 121.8438 -89.4588) (xy 121.8438 -89.6112) (xy 121.2342 -89.6112) (xy 121.2342 -89.4588)
				)
			)
		)
	)
	(footprint ""
		(layer "F.Cu")
		(at 162.569906 -106.13009)
		(property "Reference" "ME11"
			(at 0.625094 4.31546 0)
			(unlocked yes)
			(layer "F.SilkS")
			(effects
				(font
					(size 0.7874 0.5842)
					(thickness 0.1524)
				)
			)
		)
		(property "Value" ""
			(at 0 0 0)
			(layer "F.Fab")
			(effects
				(font
					(size 1.27 1.27)
				)
			)
		)
		(property "Device Type" "MEC_MTH8-MTH125C236N_V8-MTH125A"
			(at 0 5.08127 0)
			(unlocked yes)
			(layer "F.Fab")
			(hide yes)
			(effects
				(font
					(size 0.7874 0.5842)
					(thickness 0.1524)
				)
			)
		)
		(duplicate_pad_numbers_are_jumpers no)
		(fp_poly
			(pts
				(arc
					(start 3.5052 0)
					(mid -3.5052 0)
					(end 3.5052 0)
				)
			)
			(stroke
				(width 0)
				(type default)
			)
			(fill no)
			(layer "B.CrtYd")
		)
		(fp_poly
			(pts
				(arc
					(start 3.5052 0)
					(mid -3.5052 0)
					(end 3.5052 0)
				)
			)
			(stroke
				(width 0)
				(type default)
			)
			(fill no)
			(layer "F.CrtYd")
		)
		(fp_circle
			(center 0 0)
			(end 2.9972 0)
			(stroke
				(width 0.1)
				(type default)
			)
			(fill no)
			(layer "B.Fab")
		)
		(fp_circle
			(center 0 0)
			(end 2.9972 0)
			(stroke
				(width 0.1)
				(type default)
			)
			(fill no)
			(layer "F.Fab")
		)
		(pad "" np_thru_hole circle
			(at 0 0)
			(size 2.921 2.921)
			(drill 3.175)
			(layers "*.Cu" "*.Mask")
			(padstack
				(mode front_inner_back)
				(layer "Inner"
					(shape circle)
					(size 2.921 2.921)
					(clearance 0.4445)
				)
				(layer "B.Cu"
					(shape circle)
					(size 2.921 2.921)
				)
			)
		)
		(pad "1" thru_hole circle
			(at 0 -2.4511)
			(size 0.6096 0.6096)
			(drill 0.3048)
			(layers "*.Cu" "*.Mask")
			(remove_unused_layers no)
			(net "SG")
			(padstack
				(mode front_inner_back)
				(layer "Inner"
					(shape circle)
					(size 0.6096 0.6096)
					(clearance 0.1143)
				)
				(layer "B.Cu"
					(shape circle)
					(size 0.6096 0.6096)
				)
			)
		)
		(pad "2" thru_hole circle
			(at 1.733296 -1.733296)
			(size 0.6096 0.6096)
			(drill 0.3048)
			(layers "*.Cu" "*.Mask")
			(remove_unused_layers no)
			(net "SG")
			(padstack
				(mode front_inner_back)
				(layer "Inner"
					(shape circle)
					(size 0.6096 0.6096)
					(clearance 0.1143)
				)
				(layer "B.Cu"
					(shape circle)
					(size 0.6096 0.6096)
				)
			)
		)
		(pad "3" thru_hole circle
			(at 2.4511 0)
			(size 0.6096 0.6096)
			(drill 0.3048)
			(layers "*.Cu" "*.Mask")
			(remove_unused_layers no)
			(net "SG")
			(padstack
				(mode front_inner_back)
				(layer "Inner"
					(shape circle)
					(size 0.6096 0.6096)
					(clearance 0.1143)
				)
				(layer "B.Cu"
					(shape circle)
					(size 0.6096 0.6096)
				)
			)
		)
		(pad "4" thru_hole circle
			(at 1.733296 1.733296)
			(size 0.6096 0.6096)
			(drill 0.3048)
			(layers "*.Cu" "*.Mask")
			(remove_unused_layers no)
			(net "SG")
			(padstack
				(mode front_inner_back)
				(layer "Inner"
					(shape circle)
					(size 0.6096 0.6096)
					(clearance 0.1143)
				)
				(layer "B.Cu"
					(shape circle)
					(size 0.6096 0.6096)
				)
			)
		)
		(pad "5" thru_hole circle
			(at 0 2.4511)
			(size 0.6096 0.6096)
			(drill 0.3048)
			(layers "*.Cu" "*.Mask")
			(remove_unused_layers no)
			(net "SG")
			(padstack
				(mode front_inner_back)
				(layer "Inner"
					(shape circle)
					(size 0.6096 0.6096)
					(clearance 0.1143)
				)
				(layer "B.Cu"
					(shape circle)
					(size 0.6096 0.6096)
				)
			)
		)
		(pad "6" thru_hole circle
			(at -1.733296 1.733296)
			(size 0.6096 0.6096)
			(drill 0.3048)
			(layers "*.Cu" "*.Mask")
			(remove_unused_layers no)
			(net "SG")
			(padstack
				(mode front_inner_back)
				(layer "Inner"
					(shape circle)
					(size 0.6096 0.6096)
					(clearance 0.1143)
				)
				(layer "B.Cu"
					(shape circle)
					(size 0.6096 0.6096)
				)
			)
		)
		(pad "7" thru_hole circle
			(at -2.4511 0)
			(size 0.6096 0.6096)
			(drill 0.3048)
			(layers "*.Cu" "*.Mask")
			(remove_unused_layers no)
			(net "SG")
			(padstack
				(mode front_inner_back)
				(layer "Inner"
					(shape circle)
					(size 0.6096 0.6096)
					(clearance 0.1143)
				)
				(layer "B.Cu"
					(shape circle)
					(size 0.6096 0.6096)
				)
			)
		)
		(pad "8" thru_hole circle
			(at -1.733296 -1.733296)
			(size 0.6096 0.6096)
			(drill 0.3048)
			(layers "*.Cu" "*.Mask")
			(remove_unused_layers no)
			(net "SG")
			(padstack
				(mode front_inner_back)
				(layer "Inner"
					(shape circle)
					(size 0.6096 0.6096)
					(clearance 0.1143)
				)
				(layer "B.Cu"
					(shape circle)
					(size 0.6096 0.6096)
				)
			)
		)
		(zone
			(layers "F.Cu" "B.Cu" "In1.Cu" "In2.Cu" "In3.Cu" "In4.Cu" "In5.Cu" "In6.Cu"
				"In7.Cu" "In8.Cu"
			)
			(hatch none 0.5)
			(connect_pads
				(clearance 0)
			)
			(min_thickness 0.25)
			(keepout
				(tracks not_allowed)
				(vias allowed)
				(pads allowed)
				(copperpour not_allowed)
				(footprints allowed)
			)
			(placement
				(enabled no)
				(sheetname "")
			)
			(fill
				(thermal_gap 0.5)
				(thermal_bridge_width 0.5)
				(island_removal_mode 0)
			)
			(polygon
				(pts
					(arc
						(start 164.462206 -106.13009)
						(mid 160.677606 -106.13009)
						(end 164.462206 -106.13009)
					)
				)
			)
		)
	)
	(footprint ""
		(layer "F.Cu")
		(at 48.514 -130.683)
		(property "Reference" "SP53"
			(at 0 0 0)
			(layer "F.SilkS")
			(hide yes)
			(effects
				(font
					(size 1.27 1.27)
				)
			)
		)
		(property "Value" ""
			(at 0 0 0)
			(layer "F.Fab")
			(effects
				(font
					(size 1.27 1.27)
				)
			)
		)
		(duplicate_pad_numbers_are_jumpers no)
	)
	(footprint ""
		(layer "F.Cu")
		(at 87.3252 -106.7308 180)
		(property "Reference" "L8"
			(at 0.889 1.30683 0)
			(unlocked yes)
			(layer "F.SilkS")
			(effects
				(font
					(size 0.7874 0.5842)
					(thickness 0.1524)
				)
				(justify left)
			)
		)
		(property "Value" "VAL*"
			(at -0.9398 3.70967 180)
			(unlocked yes)
			(layer "F.Fab")
			(hide yes)
			(effects
				(font
					(size 0.7874 0.5842)
					(thickness 0.1524)
				)
				(justify left)
			)
		)
		(property "Tolerance" "TOL*"
			(at -0.9906 5.00507 180)
			(unlocked yes)
			(layer "Cmts.User")
			(hide yes)
			(effects
				(font
					(size 0.7874 0.5842)
					(thickness 0.1524)
				)
				(justify left)
			)
		)
		(property "User Part Number" "PARTNUM*"
			(at -2.54 2.46507 180)
			(unlocked yes)
			(layer "Cmts.User")
			(hide yes)
			(effects
				(font
					(size 0.7874 0.5842)
					(thickness 0.1524)
				)
				(justify left)
			)
		)
		(property "Device Type" "FERRITEBEAD-G191-10101-01,26OHA"
			(at -0.9906 1.22047 180)
			(unlocked yes)
			(layer "F.Fab")
			(hide yes)
			(effects
				(font
					(size 0.7874 0.5842)
					(thickness 0.1524)
				)
				(justify left)
			)
		)
		(duplicate_pad_numbers_are_jumpers no)
		(fp_line
			(start 1.3208 0.7112)
			(end -1.3208 0.7112)
			(stroke
				(width 0.1)
				(type default)
			)
			(layer "F.SilkS")
		)
		(fp_line
			(start 1.3208 -0.7112)
			(end 1.3208 0.7112)
			(stroke
				(width 0.1)
				(type default)
			)
			(layer "F.SilkS")
		)
		(fp_line
			(start -1.3208 0.7112)
			(end -1.3208 -0.7112)
			(stroke
				(width 0.1)
				(type default)
			)
			(layer "F.SilkS")
		)
		(fp_line
			(start -1.3208 -0.7112)
			(end 1.3208 -0.7112)
			(stroke
				(width 0.1)
				(type default)
			)
			(layer "F.SilkS")
		)
		(fp_rect
			(start -1.3208 0.7112)
			(end 1.3208 -0.7112)
			(stroke
				(width 0)
				(type default)
			)
			(fill no)
			(layer "F.CrtYd")
		)
		(fp_line
			(start 0.8128 0.4572)
			(end -0.8128 0.4572)
			(stroke
				(width 0.1)
				(type default)
			)
			(layer "F.Fab")
		)
		(fp_line
			(start 0.8128 -0.4572)
			(end 0.8128 0.4572)
			(stroke
				(width 0.1)
				(type default)
			)
			(layer "F.Fab")
		)
		(fp_line
			(start -0.8128 0.4572)
			(end -0.8128 -0.4572)
			(stroke
				(width 0.1)
				(type default)
			)
			(layer "F.Fab")
		)
		(fp_line
			(start -0.8128 -0.4572)
			(end 0.8128 -0.4572)
			(stroke
				(width 0.1)
				(type default)
			)
			(layer "F.Fab")
		)
		(pad "1" smd rect
			(at -0.6858 0 180)
			(size 0.762 0.8636)
			(layers "F.Cu" "F.Mask" "F.Paste")
			(net "XP12R0V")
		)
		(pad "2" smd rect
			(at 0.6858 0 180)
			(size 0.762 0.8636)
			(layers "F.Cu" "F.Mask" "F.Paste")
			(net "VIN_XP3R3")
		)
		(zone
			(layer "F.Cu")
			(hatch none 0.5)
			(connect_pads
				(clearance 0)
			)
			(min_thickness 0.25)
			(keepout
				(tracks not_allowed)
				(vias allowed)
				(pads allowed)
				(copperpour not_allowed)
				(footprints allowed)
			)
			(placement
				(enabled no)
				(sheetname "")
			)
			(fill
				(thermal_gap 0.5)
				(thermal_bridge_width 0.5)
				(island_removal_mode 0)
			)
			(polygon
				(pts
					(xy 87.4776 -107.188) (xy 87.1728 -107.188) (xy 87.1728 -106.2736) (xy 87.4776 -106.2736)
				)
			)
		)
		(zone
			(layer "F.Cu")
			(hatch none 0.5)
			(connect_pads
				(clearance 0)
			)
			(min_thickness 0.25)
			(keepout
				(tracks allowed)
				(vias not_allowed)
				(pads allowed)
				(copperpour not_allowed)
				(footprints allowed)
			)
			(placement
				(enabled no)
				(sheetname "")
			)
			(fill
				(thermal_gap 0.5)
				(thermal_bridge_width 0.5)
				(island_removal_mode 0)
			)
			(polygon
				(pts
					(xy 87.4776 -107.188) (xy 87.1728 -107.188) (xy 87.1728 -106.2736) (xy 87.4776 -106.2736)
				)
			)
		)
	)
)
